(kicad_pcb
	(version 20260206)
	(generator "pcbnew")
	(generator_version "10.0")
	(general
		(thickness 1.6)
		(legacy_teardrops no)
	)
	(paper "A4")
	(title_block
		(title "04192023_DAF0TMB3IC0_F0TG_MB_C_brd_V02_OCP.brd")
		(comment 1 "Grand Teton / footprints 1915-1922 of 8354")
	)
	(layers
		(0 "F.Cu" signal "TOP")
		(4 "In1.Cu" signal "GND")
		(6 "In2.Cu" signal "IN1")
		(8 "In3.Cu" signal "GND1")
		(10 "In4.Cu" signal "IN2")
		(12 "In5.Cu" signal "GND2")
		(14 "In6.Cu" signal "IN3")
		(16 "In7.Cu" signal "GND3")
		(18 "In8.Cu" signal "VCC")
		(20 "In9.Cu" signal "VCC1")
		(22 "In10.Cu" signal "GND4")
		(24 "In11.Cu" signal "IN4")
		(26 "In12.Cu" signal "GND5")
		(28 "In13.Cu" signal "IN5")
		(30 "In14.Cu" signal "GND6")
		(32 "In15.Cu" signal "IN6")
		(34 "In16.Cu" signal "GND7")
		(2 "B.Cu" signal "BOTTOM")
		(9 "F.Adhes" user "F.Adhesive")
		(11 "B.Adhes" user "B.Adhesive")
		(13 "F.Paste" user "Package Geometry/Pastemask Top")
		(15 "B.Paste" user "Package Geometry/Pastemask Bottom")
		(5 "F.SilkS" user "Ref Des/Silkscreen Top")
		(7 "B.SilkS" user "Ref Des/Silkscreen Bottom")
		(1 "F.Mask" user "Board Geometry/Soldermask Top")
		(3 "B.Mask" user "Board Geometry/Soldermask Bottom")
		(17 "Dwgs.User" user "User.Drawings")
		(19 "Cmts.User" user "User.Comments")
		(21 "Eco1.User" user "User.Eco1")
		(23 "Eco2.User" user "User.Eco2")
		(25 "Edge.Cuts" user "Board Geometry/Outline")
		(27 "Margin" user)
		(31 "F.CrtYd" user "Package Geometry/Place Bound Top")
		(29 "B.CrtYd" user "Package Geometry/Place Bound Bottom")
		(35 "F.Fab" user "Ref Des/Assembly Top")
		(33 "B.Fab" user "Ref Des/Assembly Bottom")
	)
	(footprint ""
		(layer "F.Cu")
		(at 138.426952 -57.516014 180)
		(property "Reference" "R6102"
			(at 0 0 180)
			(layer "F.SilkS")
			(hide yes)
			(effects
				(font
					(size 1.27 1.27)
				)
			)
		)
		(property "Value" ""
			(at 0 0 180)
			(layer "F.Fab")
			(effects
				(font
					(size 1.27 1.27)
				)
			)
		)
		(duplicate_pad_numbers_are_jumpers no)
		(fp_line
			(start 0.7874 0.4064)
			(end -0.7874 0.4064)
			(stroke
				(width 0.1524)
				(type default)
			)
			(layer "F.SilkS")
		)
		(fp_line
			(start 0.7874 -0.4064)
			(end 0.7874 0.4064)
			(stroke
				(width 0.1524)
				(type default)
			)
			(layer "F.SilkS")
		)
		(fp_line
			(start -0.7874 0.4064)
			(end -0.7874 -0.4064)
			(stroke
				(width 0.1524)
				(type default)
			)
			(layer "F.SilkS")
		)
		(fp_line
			(start -0.7874 -0.4064)
			(end 0.7874 -0.4064)
			(stroke
				(width 0.1524)
				(type default)
			)
			(layer "F.SilkS")
		)
		(fp_line
			(start 0.67945 0.3048)
			(end 0.120396 0.3048)
			(stroke
				(width 0.1)
				(type default)
			)
			(layer "F.Fab")
		)
		(fp_line
			(start 0.67945 -0.3048)
			(end 0.67945 0.3048)
			(stroke
				(width 0.1)
				(type default)
			)
			(layer "F.Fab")
		)
		(fp_line
			(start 0.12065 -0.2794)
			(end 0.12065 -0.3048)
			(stroke
				(width 0.1)
				(type default)
			)
			(layer "F.Fab")
		)
		(fp_line
			(start 0.12065 -0.3048)
			(end 0.67945 -0.3048)
			(stroke
				(width 0.1)
				(type default)
			)
			(layer "F.Fab")
		)
		(fp_line
			(start 0.120396 0.3048)
			(end 0.120396 0.2794)
			(stroke
				(width 0.1)
				(type default)
			)
			(layer "F.Fab")
		)
		(fp_line
			(start 0.120396 0.2794)
			(end -0.12065 0.2794)
			(stroke
				(width 0.1)
				(type default)
			)
			(layer "F.Fab")
		)
		(fp_line
			(start -0.12065 0.3048)
			(end -0.67945 0.3048)
			(stroke
				(width 0.1)
				(type default)
			)
			(layer "F.Fab")
		)
		(fp_line
			(start -0.12065 0.2794)
			(end -0.12065 0.3048)
			(stroke
				(width 0.1)
				(type default)
			)
			(layer "F.Fab")
		)
		(fp_line
			(start -0.12065 -0.2794)
			(end 0.12065 -0.2794)
			(stroke
				(width 0.1)
				(type default)
			)
			(layer "F.Fab")
		)
		(fp_line
			(start -0.12065 -0.305054)
			(end -0.12065 -0.2794)
			(stroke
				(width 0.1)
				(type default)
			)
			(layer "F.Fab")
		)
		(fp_line
			(start -0.67945 0.3048)
			(end -0.67945 -0.305054)
			(stroke
				(width 0.1)
				(type default)
			)
			(layer "F.Fab")
		)
		(fp_line
			(start -0.67945 -0.305054)
			(end -0.12065 -0.305054)
			(stroke
				(width 0.1)
				(type default)
			)
			(layer "F.Fab")
		)
		(pad "1" smd circle
			(at -0.40005 0 180)
			(size 0 0)
			(layers "F.Cu" "F.Mask" "F.Paste")
			(net "SCM_JTAG_MUX_S0")
		)
		(pad "2" smd circle
			(at 0.40005 0 180)
			(size 0 0)
			(layers "F.Cu" "F.Mask" "F.Paste")
			(net "SCM_JTAG_MUX_S0_R2")
		)
	)
	(footprint ""
		(layer "F.Cu")
		(at 215.74379 -390.377934 90)
		(property "Reference" "PD111"
			(at 1.8034 -3.343148 90)
			(unlocked yes)
			(layer "F.SilkS")
			(effects
				(font
					(size 0.7874 0.5842)
					(thickness 0.1524)
				)
			)
		)
		(property "Value" ""
			(at 0 0 90)
			(layer "F.Fab")
			(effects
				(font
					(size 1.27 1.27)
				)
			)
		)
		(duplicate_pad_numbers_are_jumpers no)
		(fp_line
			(start 3.541776 -2.54)
			(end 3.541776 2.54)
			(stroke
				(width 0.1524)
				(type default)
			)
			(layer "F.SilkS")
		)
		(fp_line
			(start -3.539744 -2.54)
			(end 3.541776 -2.54)
			(stroke
				(width 0.1524)
				(type default)
			)
			(layer "F.SilkS")
		)
		(fp_line
			(start 3.541776 2.54)
			(end -3.539744 2.54)
			(stroke
				(width 0.1524)
				(type default)
			)
			(layer "F.SilkS")
		)
		(fp_line
			(start -3.539744 2.54)
			(end -3.539744 -2.54)
			(stroke
				(width 0.1524)
				(type default)
			)
			(layer "F.SilkS")
		)
		(fp_poly
			(pts
				(xy -5.651246 1.802892) (xy -5.651246 0.786892) (xy -4.635246 1.294892)
			)
			(stroke
				(width 0)
				(type default)
			)
			(fill yes)
			(layer "F.SilkS")
		)
		(fp_line
			(start 3.074924 -2.175002)
			(end 3.074924 2.175002)
			(stroke
				(width 0.1)
				(type default)
			)
			(layer "F.Fab")
		)
		(fp_line
			(start -3.074924 -2.175002)
			(end 3.074924 -2.175002)
			(stroke
				(width 0.1)
				(type default)
			)
			(layer "F.Fab")
		)
		(fp_line
			(start 3.074924 2.175002)
			(end -3.074924 2.175002)
			(stroke
				(width 0.1)
				(type default)
			)
			(layer "F.Fab")
		)
		(fp_line
			(start -3.074924 2.175002)
			(end -3.074924 -2.175002)
			(stroke
				(width 0.1)
				(type default)
			)
			(layer "F.Fab")
		)
		(fp_poly
			(pts
				(xy -4.699 0.531876) (xy -4.699 1.547876) (xy -3.683 1.039876)
			)
			(stroke
				(width 0)
				(type default)
			)
			(fill yes)
			(layer "F.Fab")
		)
		(pad "1" smd rect
			(at -2.765044 1.039876 270)
			(size 1.27 1.4224)
			(layers "F.Cu" "F.Mask" "F.Paste")
			(net "GND")
		)
		(pad "2" smd rect
			(at -2.765044 -1.039876 270)
			(size 1.27 1.4224)
			(layers "F.Cu" "F.Mask" "F.Paste")
			(net "GND")
		)
		(pad "K" smd rect
			(at 1.039876 0 270)
			(size 4.7244 4.8006)
			(layers "F.Cu" "F.Mask" "F.Paste")
			(net "P12V_AUX")
		)
	)
	(footprint ""
		(layer "F.Cu")
		(at 393.086336 -184.478168 -90)
		(property "Reference" "PR499"
			(at 0 0 270)
			(layer "F.SilkS")
			(hide yes)
			(effects
				(font
					(size 1.27 1.27)
				)
			)
		)
		(property "Value" ""
			(at 0 0 270)
			(layer "F.Fab")
			(effects
				(font
					(size 1.27 1.27)
				)
			)
		)
		(duplicate_pad_numbers_are_jumpers no)
		(fp_line
			(start -0.7874 0.4064)
			(end -0.7874 -0.4064)
			(stroke
				(width 0.1524)
				(type default)
			)
			(layer "F.SilkS")
		)
		(fp_line
			(start 0.7874 0.4064)
			(end -0.7874 0.4064)
			(stroke
				(width 0.1524)
				(type default)
			)
			(layer "F.SilkS")
		)
		(fp_line
			(start -0.7874 -0.4064)
			(end 0.7874 -0.4064)
			(stroke
				(width 0.1524)
				(type default)
			)
			(layer "F.SilkS")
		)
		(fp_line
			(start 0.7874 -0.4064)
			(end 0.7874 0.4064)
			(stroke
				(width 0.1524)
				(type default)
			)
			(layer "F.SilkS")
		)
		(fp_line
			(start -0.67945 0.3048)
			(end -0.67945 -0.305054)
			(stroke
				(width 0.1)
				(type default)
			)
			(layer "F.Fab")
		)
		(fp_line
			(start -0.12065 0.3048)
			(end -0.67945 0.3048)
			(stroke
				(width 0.1)
				(type default)
			)
			(layer "F.Fab")
		)
		(fp_line
			(start 0.120396 0.3048)
			(end 0.120396 0.2794)
			(stroke
				(width 0.1)
				(type default)
			)
			(layer "F.Fab")
		)
		(fp_line
			(start 0.67945 0.3048)
			(end 0.120396 0.3048)
			(stroke
				(width 0.1)
				(type default)
			)
			(layer "F.Fab")
		)
		(fp_line
			(start -0.12065 0.2794)
			(end -0.12065 0.3048)
			(stroke
				(width 0.1)
				(type default)
			)
			(layer "F.Fab")
		)
		(fp_line
			(start 0.120396 0.2794)
			(end -0.12065 0.2794)
			(stroke
				(width 0.1)
				(type default)
			)
			(layer "F.Fab")
		)
		(fp_line
			(start -0.12065 -0.2794)
			(end 0.12065 -0.2794)
			(stroke
				(width 0.1)
				(type default)
			)
			(layer "F.Fab")
		)
		(fp_line
			(start 0.12065 -0.2794)
			(end 0.12065 -0.3048)
			(stroke
				(width 0.1)
				(type default)
			)
			(layer "F.Fab")
		)
		(fp_line
			(start 0.12065 -0.3048)
			(end 0.67945 -0.3048)
			(stroke
				(width 0.1)
				(type default)
			)
			(layer "F.Fab")
		)
		(fp_line
			(start 0.67945 -0.3048)
			(end 0.67945 0.3048)
			(stroke
				(width 0.1)
				(type default)
			)
			(layer "F.Fab")
		)
		(fp_line
			(start -0.67945 -0.305054)
			(end -0.12065 -0.305054)
			(stroke
				(width 0.1)
				(type default)
			)
			(layer "F.Fab")
		)
		(fp_line
			(start -0.12065 -0.305054)
			(end -0.12065 -0.2794)
			(stroke
				(width 0.1)
				(type default)
			)
			(layer "F.Fab")
		)
		(pad "1" smd circle
			(at -0.40005 0 270)
			(size 0 0)
			(layers "F.Cu" "F.Mask" "F.Paste")
			(net "SW_PVDDCR_CPU0_P0_SW4_RC")
		)
		(pad "2" smd circle
			(at 0.40005 0 270)
			(size 0 0)
			(layers "F.Cu" "F.Mask" "F.Paste")
			(net "GND")
		)
	)
	(footprint ""
		(layer "F.Cu")
		(at 401.501102 -416.899344 -90)
		(property "Reference" "C6586"
			(at 0 0 270)
			(layer "F.SilkS")
			(hide yes)
			(effects
				(font
					(size 1.27 1.27)
				)
			)
		)
		(property "Value" ""
			(at 0 0 270)
			(layer "F.Fab")
			(effects
				(font
					(size 1.27 1.27)
				)
			)
		)
		(duplicate_pad_numbers_are_jumpers no)
		(fp_line
			(start -0.299974 0.150114)
			(end -0.299974 -0.150114)
			(stroke
				(width 0.1)
				(type default)
			)
			(layer "F.Fab")
		)
		(fp_line
			(start 0.299974 0.150114)
			(end -0.299974 0.150114)
			(stroke
				(width 0.1)
				(type default)
			)
			(layer "F.Fab")
		)
		(fp_line
			(start -0.299974 -0.150114)
			(end 0.299974 -0.150114)
			(stroke
				(width 0.1)
				(type default)
			)
			(layer "F.Fab")
		)
		(fp_line
			(start 0.299974 -0.150114)
			(end 0.299974 0.150114)
			(stroke
				(width 0.1)
				(type default)
			)
			(layer "F.Fab")
		)
		(pad "1" smd rect
			(at -0.2667 0 270)
			(size 0.3048 0.381)
			(layers "F.Cu" "F.Mask" "F.Paste")
			(net "P5E_CPU0_P2_TX_BUF_C_DN<10>")
		)
		(pad "2" smd rect
			(at 0.2667 0 270)
			(size 0.3048 0.381)
			(layers "F.Cu" "F.Mask" "F.Paste")
			(net "P5E_CPU0_P2_TX_BUF_DN<10>")
		)
	)
	(footprint ""
		(layer "F.Cu")
		(at 110.067344 -382.39446 180)
		(property "Reference" "C1547"
			(at 0 0 180)
			(layer "F.SilkS")
			(hide yes)
			(effects
				(font
					(size 1.27 1.27)
				)
			)
		)
		(property "Value" ""
			(at 0 0 180)
			(layer "F.Fab")
			(effects
				(font
					(size 1.27 1.27)
				)
			)
		)
		(duplicate_pad_numbers_are_jumpers no)
		(fp_line
			(start 0.299974 0.150114)
			(end -0.299974 0.150114)
			(stroke
				(width 0.1)
				(type default)
			)
			(layer "F.Fab")
		)
		(fp_line
			(start 0.299974 -0.150114)
			(end 0.299974 0.150114)
			(stroke
				(width 0.1)
				(type default)
			)
			(layer "F.Fab")
		)
		(fp_line
			(start -0.299974 0.150114)
			(end -0.299974 -0.150114)
			(stroke
				(width 0.1)
				(type default)
			)
			(layer "F.Fab")
		)
		(fp_line
			(start -0.299974 -0.150114)
			(end 0.299974 -0.150114)
			(stroke
				(width 0.1)
				(type default)
			)
			(layer "F.Fab")
		)
		(pad "1" smd rect
			(at -0.2667 0 180)
			(size 0.3048 0.381)
			(layers "F.Cu" "F.Mask" "F.Paste")
			(net "P5E_CPU1_P3_TX_C_DP<0>")
		)
		(pad "2" smd rect
			(at 0.2667 0 180)
			(size 0.3048 0.381)
			(layers "F.Cu" "F.Mask" "F.Paste")
			(net "P5E_CPU1_P3_TX_DP<0>")
		)
	)
	(footprint ""
		(layer "F.Cu")
		(at 97.074736 -119.469154 90)
		(property "Reference" "C5014"
			(at 0 0 90)
			(layer "F.SilkS")
			(hide yes)
			(effects
				(font
					(size 1.27 1.27)
				)
			)
		)
		(property "Value" ""
			(at 0 0 90)
			(layer "F.Fab")
			(effects
				(font
					(size 1.27 1.27)
				)
			)
		)
		(duplicate_pad_numbers_are_jumpers no)
		(fp_line
			(start 0.7874 -0.4064)
			(end 0.7874 0.4064)
			(stroke
				(width 0.1524)
				(type default)
			)
			(layer "F.SilkS")
		)
		(fp_line
			(start -0.7874 -0.4064)
			(end 0.7874 -0.4064)
			(stroke
				(width 0.1524)
				(type default)
			)
			(layer "F.SilkS")
		)
		(fp_line
			(start 0.7874 0.4064)
			(end -0.7874 0.4064)
			(stroke
				(width 0.1524)
				(type default)
			)
			(layer "F.SilkS")
		)
		(fp_line
			(start -0.7874 0.4064)
			(end -0.7874 -0.4064)
			(stroke
				(width 0.1524)
				(type default)
			)
			(layer "F.SilkS")
		)
		(fp_line
			(start -0.12065 -0.305054)
			(end -0.12065 -0.2794)
			(stroke
				(width 0.1)
				(type default)
			)
			(layer "F.Fab")
		)
		(fp_line
			(start -0.67945 -0.305054)
			(end -0.12065 -0.305054)
			(stroke
				(width 0.1)
				(type default)
			)
			(layer "F.Fab")
		)
		(fp_line
			(start 0.67945 -0.3048)
			(end 0.67945 0.3048)
			(stroke
				(width 0.1)
				(type default)
			)
			(layer "F.Fab")
		)
		(fp_line
			(start 0.12065 -0.3048)
			(end 0.67945 -0.3048)
			(stroke
				(width 0.1)
				(type default)
			)
			(layer "F.Fab")
		)
		(fp_line
			(start 0.12065 -0.2794)
			(end 0.12065 -0.3048)
			(stroke
				(width 0.1)
				(type default)
			)
			(layer "F.Fab")
		)
		(fp_line
			(start -0.12065 -0.2794)
			(end 0.12065 -0.2794)
			(stroke
				(width 0.1)
				(type default)
			)
			(layer "F.Fab")
		)
		(fp_line
			(start 0.120396 0.2794)
			(end -0.12065 0.2794)
			(stroke
				(width 0.1)
				(type default)
			)
			(layer "F.Fab")
		)
		(fp_line
			(start -0.12065 0.2794)
			(end -0.12065 0.3048)
			(stroke
				(width 0.1)
				(type default)
			)
			(layer "F.Fab")
		)
		(fp_line
			(start 0.67945 0.3048)
			(end 0.120396 0.3048)
			(stroke
				(width 0.1)
				(type default)
			)
			(layer "F.Fab")
		)
		(fp_line
			(start 0.120396 0.3048)
			(end 0.120396 0.2794)
			(stroke
				(width 0.1)
				(type default)
			)
			(layer "F.Fab")
		)
		(fp_line
			(start -0.12065 0.3048)
			(end -0.67945 0.3048)
			(stroke
				(width 0.1)
				(type default)
			)
			(layer "F.Fab")
		)
		(fp_line
			(start -0.67945 0.3048)
			(end -0.67945 -0.305054)
			(stroke
				(width 0.1)
				(type default)
			)
			(layer "F.Fab")
		)
		(pad "1" smd circle
			(at -0.40005 0 90)
			(size 0 0)
			(layers "F.Cu" "F.Mask" "F.Paste")
			(net "PWRGD_P12V_MEM_R")
		)
		(pad "2" smd circle
			(at 0.40005 0 90)
			(size 0 0)
			(layers "F.Cu" "F.Mask" "F.Paste")
			(net "GND")
		)
	)
	(footprint ""
		(layer "F.Cu")
		(at 234.771946 -141.805152)
		(property "Reference" "Q63"
			(at -3.24866 -1.300988 0)
			(unlocked yes)
			(layer "F.SilkS")
			(effects
				(font
					(size 0.7874 0.5842)
					(thickness 0.1524)
				)
			)
		)
		(property "Value" ""
			(at 0 0 0)
			(layer "F.Fab")
			(effects
				(font
					(size 1.27 1.27)
				)
			)
		)
		(duplicate_pad_numbers_are_jumpers no)
		(fp_line
			(start -1.949958 -1.610106)
			(end 1.949958 -1.610106)
			(stroke
				(width 0.1524)
				(type default)
			)
			(layer "F.SilkS")
		)
		(fp_line
			(start -1.949958 1.610106)
			(end -1.949958 -1.610106)
			(stroke
				(width 0.1524)
				(type default)
			)
			(layer "F.SilkS")
		)
		(fp_line
			(start 1.949958 -1.560068)
			(end 1.949958 1.610106)
			(stroke
				(width 0.1524)
				(type default)
			)
			(layer "F.SilkS")
		)
		(fp_line
			(start 1.949958 1.610106)
			(end -1.949958 1.610106)
			(stroke
				(width 0.1524)
				(type default)
			)
			(layer "F.SilkS")
		)
		(fp_line
			(start -0.750062 -1.560068)
			(end 0.750062 -1.560068)
			(stroke
				(width 0.1)
				(type default)
			)
			(layer "F.Fab")
		)
		(fp_line
			(start -0.750062 1.560068)
			(end -0.750062 -1.560068)
			(stroke
				(width 0.1)
				(type default)
			)
			(layer "F.Fab")
		)
		(fp_line
			(start 0.750062 -1.560068)
			(end 0.750062 1.560068)
			(stroke
				(width 0.1)
				(type default)
			)
			(layer "F.Fab")
		)
		(fp_line
			(start 0.750062 1.560068)
			(end -0.750062 1.560068)
			(stroke
				(width 0.1)
				(type default)
			)
			(layer "F.Fab")
		)
		(pad "D" smd rect
			(at 1.100074 0 270)
			(size 1.016 1.4224)
			(layers "F.Cu" "F.Mask" "F.Paste")
			(net "FM_PLD_CPU0_PRSNT_HDT_N")
		)
		(pad "G" smd rect
			(at -1.100074 -0.94996 270)
			(size 1.016 1.4224)
			(layers "F.Cu" "F.Mask" "F.Paste")
			(net "CPU0_HDT_BYPASS_SEL")
		)
		(pad "S" smd rect
			(at -1.100074 0.94996 270)
			(size 1.016 1.4224)
			(layers "F.Cu" "F.Mask" "F.Paste")
			(net "GND")
		)
	)
	(footprint ""
		(layer "F.Cu")
		(at 441.31103 -394.302234 180)
		(property "Reference" "PC6564"
			(at 0 0 180)
			(layer "F.SilkS")
			(hide yes)
			(effects
				(font
					(size 1.27 1.27)
				)
			)
		)
		(property "Value" ""
			(at 0 0 180)
			(layer "F.Fab")
			(effects
				(font
					(size 1.27 1.27)
				)
			)
		)
		(duplicate_pad_numbers_are_jumpers no)
		(fp_line
			(start 0.7874 0.4064)
			(end -0.7874 0.4064)
			(stroke
				(width 0.1524)
				(type default)
			)
			(layer "F.SilkS")
		)
		(fp_line
			(start 0.7874 -0.4064)
			(end 0.7874 0.4064)
			(stroke
				(width 0.1524)
				(type default)
			)
			(layer "F.SilkS")
		)
		(fp_line
			(start -0.7874 0.4064)
			(end -0.7874 -0.4064)
			(stroke
				(width 0.1524)
				(type default)
			)
			(layer "F.SilkS")
		)
		(fp_line
			(start -0.7874 -0.4064)
			(end 0.7874 -0.4064)
			(stroke
				(width 0.1524)
				(type default)
			)
			(layer "F.SilkS")
		)
		(fp_line
			(start 0.67945 0.3048)
			(end 0.120396 0.3048)
			(stroke
				(width 0.1)
				(type default)
			)
			(layer "F.Fab")
		)
		(fp_line
			(start 0.67945 -0.3048)
			(end 0.67945 0.3048)
			(stroke
				(width 0.1)
				(type default)
			)
			(layer "F.Fab")
		)
		(fp_line
			(start 0.12065 -0.2794)
			(end 0.12065 -0.3048)
			(stroke
				(width 0.1)
				(type default)
			)
			(layer "F.Fab")
		)
		(fp_line
			(start 0.12065 -0.3048)
			(end 0.67945 -0.3048)
			(stroke
				(width 0.1)
				(type default)
			)
			(layer "F.Fab")
		)
		(fp_line
			(start 0.120396 0.3048)
			(end 0.120396 0.2794)
			(stroke
				(width 0.1)
				(type default)
			)
			(layer "F.Fab")
		)
		(fp_line
			(start 0.120396 0.2794)
			(end -0.12065 0.2794)
			(stroke
				(width 0.1)
				(type default)
			)
			(layer "F.Fab")
		)
		(fp_line
			(start -0.12065 0.3048)
			(end -0.67945 0.3048)
			(stroke
				(width 0.1)
				(type default)
			)
			(layer "F.Fab")
		)
		(fp_line
			(start -0.12065 0.2794)
			(end -0.12065 0.3048)
			(stroke
				(width 0.1)
				(type default)
			)
			(layer "F.Fab")
		)
		(fp_line
			(start -0.12065 -0.2794)
			(end 0.12065 -0.2794)
			(stroke
				(width 0.1)
				(type default)
			)
			(layer "F.Fab")
		)
		(fp_line
			(start -0.12065 -0.305054)
			(end -0.12065 -0.2794)
			(stroke
				(width 0.1)
				(type default)
			)
			(layer "F.Fab")
		)
		(fp_line
			(start -0.67945 0.3048)
			(end -0.67945 -0.305054)
			(stroke
				(width 0.1)
				(type default)
			)
			(layer "F.Fab")
		)
		(fp_line
			(start -0.67945 -0.305054)
			(end -0.12065 -0.305054)
			(stroke
				(width 0.1)
				(type default)
			)
			(layer "F.Fab")
		)
		(pad "1" smd circle
			(at -0.40005 0 180)
			(size 0 0)
			(layers "F.Cu" "F.Mask" "F.Paste")
			(net "SW_P0V9_RETIMER_CPU0_SW1")
		)
		(pad "2" smd circle
			(at 0.40005 0 180)
			(size 0 0)
			(layers "F.Cu" "F.Mask" "F.Paste")
			(net "SW_P0V9_RETIMER_CPU0_SW1_RC")
		)
	)
)
